# S9S_MB_2U (Grand Teton) — schematic netlist excerpt (pin names and nets, part order shuffled) for the footprints in the layout excerpt that follows; sources: Cadence DE-HDL packaged netlist, KiCad conversion of 03242023_DA0F0TMBIJ0_F0T_Motherboard_J_brd_V01_OCP.brd

J107  CONN112_10137002101LF  CONN112_10137002-101LF IO  pkg HSD_F112D8_P2W1-2_RDH  page 138
  A1  = NC_J107_A1
  A2  = GND
  A3  = NC_J107_A3
  A4  = GND
  A5  = NC_J107_A5
  A6  = GND
  A7  = SWB_HSC_PWRGD
  A8  = GND
  B1  = GND
  B2  = P5E_CPU0_PE0_RX_DN<6>
  B3  = GND
  B4  = P5E_CPU0_PE0_RX_DN<4>
  B5  = GND
  B6  = P5E_CPU0_PE0_RX_DN<2>
  B7  = GND
  B8  = P5E_CPU0_PE0_RX_DN<0>
  C1  = P5E_CPU0_PE0_RX_DN<7>
  C2  = P5E_CPU0_PE0_RX_DP<6>
  C3  = P5E_CPU0_PE0_RX_DN<5>
  C4  = P5E_CPU0_PE0_RX_DP<4>
  C5  = P5E_CPU0_PE0_RX_DP<3>
  C6  = P5E_CPU0_PE0_RX_DP<2>
  C7  = P5E_CPU0_PE0_RX_DP<1>
  C8  = P5E_CPU0_PE0_RX_DP<0>
  D1  = P5E_CPU0_PE0_RX_DP<7>
  D2  = GND
  D3  = P5E_CPU0_PE0_RX_DP<5>
  D4  = GND
  D5  = P5E_CPU0_PE0_RX_DN<3>
  D6  = GND
  D7  = P5E_CPU0_PE0_RX_DN<1>
  D8  = GND
  E1  = GND
  E2  = P5E_CPU0_PE4_RX_DP<9>
  E3  = GND
  E4  = P5E_CPU0_PE4_RX_DP<11>
  E5  = GND
  E6  = P5E_CPU0_PE4_RX_DP<13>
  E7  = GND
  E8  = P5E_CPU0_PE4_RX_DP<15>
  F1  = P5E_CPU0_PE4_RX_DN<8>
  F2  = P5E_CPU0_PE4_RX_DN<9>
  F3  = P5E_CPU0_PE4_RX_DN<10>
  F4  = P5E_CPU0_PE4_RX_DN<11>
  F5  = P5E_CPU0_PE4_RX_DN<12>
  F6  = P5E_CPU0_PE4_RX_DN<13>
  F7  = P5E_CPU0_PE4_RX_DN<14>
  F8  = P5E_CPU0_PE4_RX_DN<15>
  G1  = P5E_CPU0_PE4_RX_DP<8>
  G2  = GND
  G3  = P5E_CPU0_PE4_RX_DP<10>
  G4  = GND
  G5  = P5E_CPU0_PE4_RX_DP<12>
  G6  = GND
  G7  = P5E_CPU0_PE4_RX_DP<14>
  G8  = GND
  H1  = GND
  H2  = P5E_CPU0_PE0_TX_C_DN<6>
  H3  = GND
  H4  = P5E_CPU0_PE0_TX_C_DN<4>
  H5  = GND
  H6  = P5E_CPU0_PE0_TX_C_DN<2>
  H7  = GND
  H8  = P5E_CPU0_PE0_TX_C_DN<0>
  I1  = P5E_CPU0_PE0_TX_C_DN<7>
  I2  = P5E_CPU0_PE0_TX_C_DP<6>
  I3  = P5E_CPU0_PE0_TX_C_DN<5>
  I4  = P5E_CPU0_PE0_TX_C_DP<4>
  I5  = P5E_CPU0_PE0_TX_C_DN<3>
  I6  = P5E_CPU0_PE0_TX_C_DP<2>
  I7  = P5E_CPU0_PE0_TX_C_DN<1>
  I8  = P5E_CPU0_PE0_TX_C_DP<0>
  J1  = P5E_CPU0_PE0_TX_C_DP<7>
  J2  = GND
  J3  = P5E_CPU0_PE0_TX_C_DP<5>
  J4  = GND
  J5  = P5E_CPU0_PE0_TX_C_DP<3>
  J6  = GND
  J7  = P5E_CPU0_PE0_TX_C_DP<1>
  J8  = GND
  K1  = GND
  K2  = P5E_CPU0_PE4_TX_C_DN<9>
  K3  = GND
  K4  = P5E_CPU0_PE4_TX_C_DP<11>
  K5  = GND
  K6  = P5E_CPU0_PE4_TX_C_DN<13>
  K7  = GND
  K8  = P5E_CPU0_PE4_TX_C_DN<15>
  L1  = P5E_CPU0_PE4_TX_C_DN<8>
  L2  = P5E_CPU0_PE4_TX_C_DP<9>
  L3  = P5E_CPU0_PE4_TX_C_DN<10>
  L4  = P5E_CPU0_PE4_TX_C_DN<11>
  L5  = P5E_CPU0_PE4_TX_C_DN<12>
  L6  = P5E_CPU0_PE4_TX_C_DP<13>
  L7  = P5E_CPU0_PE4_TX_C_DN<14>
  L8  = P5E_CPU0_PE4_TX_C_DP<15>
  M1  = P5E_CPU0_PE4_TX_C_DP<8>
  M2  = GND
  M3  = P5E_CPU0_PE4_TX_C_DP<10>
  M4  = GND
  M5  = P5E_CPU0_PE4_TX_C_DP<12>
  M6  = GND
  M7  = P5E_CPU0_PE4_TX_C_DP<14>
  M8  = GND
  N1  = GND
  N2  = PRSNT_CABLE_SWB_B2_N
  N3  = GND
  N4  = NC_J107_N4
  N5  = GND
  N6  = NC_J107_N6
  N7  = GND
  N8  = SWB_HSC_EN_BUF

(kicad_pcb
	(version 20260206)
	(generator "pcbnew")
	(generator_version "10.0")
	(general
		(thickness 1.6)
		(legacy_teardrops no)
	)
	(paper "A4")
	(title_block
		(title "03242023_DA0F0TMBIJ0_F0T_Motherboard_J_brd_V01_OCP.brd")
		(comment 1 "Grand Teton / footprint 950 of 6105 (J107), pads 32-48 of 48")
	)
	(layers
		(0 "F.Cu" signal "TOP")
		(4 "In1.Cu" signal "GND")
		(6 "In2.Cu" signal "IN1")
		(8 "In3.Cu" signal "GND1")
		(10 "In4.Cu" signal "IN2")
		(12 "In5.Cu" signal "GND2")
		(14 "In6.Cu" signal "IN3")
		(16 "In7.Cu" signal "GND3")
		(18 "In8.Cu" signal "VCC")
		(20 "In9.Cu" signal "VCC1")
		(22 "In10.Cu" signal "GND4")
		(24 "In11.Cu" signal "IN4")
		(26 "In12.Cu" signal "GND5")
		(28 "In13.Cu" signal "IN5")
		(30 "In14.Cu" signal "GND6")
		(32 "In15.Cu" signal "IN6")
		(34 "In16.Cu" signal "GND7")
		(2 "B.Cu" signal "BOTTOM")
		(9 "F.Adhes" user "F.Adhesive")
		(11 "B.Adhes" user "B.Adhesive")
		(13 "F.Paste" user "Package Geometry/Pastemask Top")
		(15 "B.Paste" user "Package Geometry/Pastemask Bottom")
		(5 "F.SilkS" user "Ref Des/Silkscreen Top")
		(7 "B.SilkS" user "Ref Des/Silkscreen Bottom")
		(1 "F.Mask" user "Board Geometry/Soldermask Top")
		(3 "B.Mask" user "Board Geometry/Soldermask Bottom")
		(17 "Dwgs.User" user "User.Drawings")
		(19 "Cmts.User" user "User.Comments")
		(21 "Eco1.User" user "User.Eco1")
		(23 "Eco2.User" user "User.Eco2")
		(25 "Edge.Cuts" user "Board Geometry/Outline")
		(27 "Margin" user)
		(31 "F.CrtYd" user "Package Geometry/Place Bound Top")
		(29 "B.CrtYd" user "Package Geometry/Place Bound Bottom")
		(35 "F.Fab" user "Ref Des/Assembly Top")
		(33 "B.Fab" user "Ref Des/Assembly Bottom")
	)
	(footprint ""
		(layer "F.Cu")
		(at 331.650086 -440.489848)
		(property "Reference" "J107"
			(at 3.42392 23.088092 0)
			(unlocked yes)
			(layer "F.SilkS")
			(effects
				(font
					(size 0.7874 0.5842)
					(thickness 0.1524)
				)
				(justify left)
			)
		)
		(property "Value" ""
			(at 0 0 0)
			(layer "F.Fab")
			(effects
				(font
					(size 1.27 1.27)
				)
			)
		)
		(duplicate_pad_numbers_are_jumpers no)
		(pad "J8" thru_hole circle
			(at 13.999972 10.999978 180)
			(size 0.906272 0.906272)
			(drill 0.499872)
			(layers "*.Cu" "*.Mask")
			(remove_unused_layers no)
			(net "GND")
			(clearance 0.0508)
			(thermal_gap 0.0508)
		)
		(pad "K1" thru_hole circle
			(at 0 11.999976 180)
			(size 0.906272 0.906272)
			(drill 0.499872)
			(layers "*.Cu" "*.Mask")
			(remove_unused_layers no)
			(net "GND")
			(clearance 0.0508)
			(thermal_gap 0.0508)
		)
		(pad "K3" thru_hole circle
			(at 3.999992 11.999976 180)
			(size 0.906272 0.906272)
			(drill 0.499872)
			(layers "*.Cu" "*.Mask")
			(remove_unused_layers no)
			(net "GND")
			(clearance 0.0508)
			(thermal_gap 0.0508)
		)
		(pad "K5" thru_hole circle
			(at 7.999984 11.999976 180)
			(size 0.906272 0.906272)
			(drill 0.499872)
			(layers "*.Cu" "*.Mask")
			(remove_unused_layers no)
			(net "GND")
			(clearance 0.0508)
			(thermal_gap 0.0508)
		)
		(pad "K7" thru_hole circle
			(at 11.999976 11.999976 180)
			(size 0.906272 0.906272)
			(drill 0.499872)
			(layers "*.Cu" "*.Mask")
			(remove_unused_layers no)
			(net "GND")
			(clearance 0.0508)
			(thermal_gap 0.0508)
		)
		(pad "M2" thru_hole circle
			(at 1.999996 14.59992 180)
			(size 0.906272 0.906272)
			(drill 0.499872)
			(layers "*.Cu" "*.Mask")
			(remove_unused_layers no)
			(net "GND")
			(clearance 0.0508)
			(thermal_gap 0.0508)
		)
		(pad "M4" thru_hole circle
			(at 5.999988 14.59992 180)
			(size 0.906272 0.906272)
			(drill 0.499872)
			(layers "*.Cu" "*.Mask")
			(remove_unused_layers no)
			(net "GND")
			(clearance 0.0508)
			(thermal_gap 0.0508)
		)
		(pad "M6" thru_hole circle
			(at 9.99998 14.59992 180)
			(size 0.906272 0.906272)
			(drill 0.499872)
			(layers "*.Cu" "*.Mask")
			(remove_unused_layers no)
			(net "GND")
			(clearance 0.0508)
			(thermal_gap 0.0508)
		)
		(pad "M8" thru_hole circle
			(at 13.999972 14.59992 180)
			(size 0.906272 0.906272)
			(drill 0.499872)
			(layers "*.Cu" "*.Mask")
			(remove_unused_layers no)
			(net "GND")
			(clearance 0.0508)
			(thermal_gap 0.0508)
		)
		(pad "N1" thru_hole circle
			(at 0 15.599918 180)
			(size 0.906272 0.906272)
			(drill 0.499872)
			(layers "*.Cu" "*.Mask")
			(remove_unused_layers no)
			(net "GND")
			(clearance 0.0508)
			(thermal_gap 0.0508)
		)
		(pad "N2" thru_hole circle
			(at 1.999996 15.80007 180)
			(size 0.766318 0.766318)
			(drill 0.359918)
			(layers "*.Cu" "*.Mask")
			(remove_unused_layers no)
			(net "PRSNT_CABLE_SWB_B2_N")
			(clearance 0.0508)
			(thermal_gap 0.0508)
		)
		(pad "N3" thru_hole circle
			(at 3.999992 15.599918 180)
			(size 0.906272 0.906272)
			(drill 0.499872)
			(layers "*.Cu" "*.Mask")
			(remove_unused_layers no)
			(net "GND")
			(clearance 0.0508)
			(thermal_gap 0.0508)
		)
		(pad "N4" thru_hole circle
			(at 5.999988 15.80007 180)
			(size 0.766318 0.766318)
			(drill 0.359918)
			(layers "*.Cu" "*.Mask")
			(remove_unused_layers no)
			(net "NC_J107_N4")
			(clearance 0.0508)
			(thermal_gap 0.0508)
		)
		(pad "N5" thru_hole circle
			(at 7.999984 15.599918 180)
			(size 0.906272 0.906272)
			(drill 0.499872)
			(layers "*.Cu" "*.Mask")
			(remove_unused_layers no)
			(net "GND")
			(clearance 0.0508)
			(thermal_gap 0.0508)
		)
		(pad "N6" thru_hole circle
			(at 9.99998 15.80007 180)
			(size 0.766318 0.766318)
			(drill 0.359918)
			(layers "*.Cu" "*.Mask")
			(remove_unused_layers no)
			(net "NC_J107_N6")
			(clearance 0.0508)
			(thermal_gap 0.0508)
		)
		(pad "N7" thru_hole circle
			(at 11.999976 15.599918 180)
			(size 0.906272 0.906272)
			(drill 0.499872)
			(layers "*.Cu" "*.Mask")
			(remove_unused_layers no)
			(net "GND")
			(clearance 0.0508)
			(thermal_gap 0.0508)
		)
		(pad "N8" thru_hole circle
			(at 13.999972 15.80007 180)
			(size 0.766318 0.766318)
			(drill 0.359918)
			(layers "*.Cu" "*.Mask")
			(remove_unused_layers no)
			(net "SWB_HSC_EN_BUF")
			(clearance 0.0508)
			(thermal_gap 0.0508)
		)
	)
)
